(kicad_pcb
	(version 20260206)
	(generator "pcbnew")
	(generator_version "10.0")
	(general
		(thickness 1.6)
		(legacy_teardrops no)
	)
	(paper "A4")
	(title_block
		(title "12092022_DA0F0TMDCD0_F0T_Management_Board_D_brd_V3_OCP.brd")
		(comment 1 "Grand Teton / footprints 49-55 of 1440")
	)
	(layers
		(0 "F.Cu" signal "TOP")
		(4 "In1.Cu" signal "GND")
		(6 "In2.Cu" signal "IN1")
		(8 "In3.Cu" signal "GND1")
		(10 "In4.Cu" signal "IN2")
		(12 "In5.Cu" signal "VCC")
		(14 "In6.Cu" signal "VCC1")
		(16 "In7.Cu" signal "IN3")
		(18 "In8.Cu" signal "GND2")
		(20 "In9.Cu" signal "IN4")
		(22 "In10.Cu" signal "GND3")
		(2 "B.Cu" signal "BOTTOM")
		(9 "F.Adhes" user "F.Adhesive")
		(11 "B.Adhes" user "B.Adhesive")
		(13 "F.Paste" user "Package Geometry/Pastemask Top")
		(15 "B.Paste" user "Package Geometry/Pastemask Bottom")
		(5 "F.SilkS" user "Ref Des/Silkscreen Top")
		(7 "B.SilkS" user "Ref Des/Silkscreen Bottom")
		(1 "F.Mask" user "Board Geometry/Soldermask Top")
		(3 "B.Mask" user "Board Geometry/Soldermask Bottom")
		(17 "Dwgs.User" user "User.Drawings")
		(19 "Cmts.User" user "User.Comments")
		(21 "Eco1.User" user "User.Eco1")
		(23 "Eco2.User" user "User.Eco2")
		(25 "Edge.Cuts" user "Board Geometry/Outline")
		(27 "Margin" user)
		(31 "F.CrtYd" user "Package Geometry/Place Bound Top")
		(29 "B.CrtYd" user "Package Geometry/Place Bound Bottom")
		(35 "F.Fab" user "Ref Des/Assembly Top")
		(33 "B.Fab" user "Ref Des/Assembly Bottom")
	)
	(footprint ""
		(layer "F.Cu")
		(at 48.650652 -63.966344 -90)
		(property "Reference" "R233"
			(at 0 0 270)
			(layer "F.SilkS")
			(hide yes)
			(effects
				(font
					(size 1.27 1.27)
				)
			)
		)
		(property "Value" ""
			(at 0 0 270)
			(layer "F.Fab")
			(effects
				(font
					(size 1.27 1.27)
				)
			)
		)
		(duplicate_pad_numbers_are_jumpers no)
		(fp_line
			(start -0.7874 0.4064)
			(end -0.7874 -0.4064)
			(stroke
				(width 0.1524)
				(type default)
			)
			(layer "F.SilkS")
		)
		(fp_line
			(start 0.7874 0.4064)
			(end -0.7874 0.4064)
			(stroke
				(width 0.1524)
				(type default)
			)
			(layer "F.SilkS")
		)
		(fp_line
			(start -0.7874 -0.4064)
			(end 0.7874 -0.4064)
			(stroke
				(width 0.1524)
				(type default)
			)
			(layer "F.SilkS")
		)
		(fp_line
			(start 0.7874 -0.4064)
			(end 0.7874 0.4064)
			(stroke
				(width 0.1524)
				(type default)
			)
			(layer "F.SilkS")
		)
		(fp_line
			(start -0.67945 0.3048)
			(end -0.67945 -0.305054)
			(stroke
				(width 0.1)
				(type default)
			)
			(layer "F.Fab")
		)
		(fp_line
			(start -0.12065 0.3048)
			(end -0.67945 0.3048)
			(stroke
				(width 0.1)
				(type default)
			)
			(layer "F.Fab")
		)
		(fp_line
			(start 0.120396 0.3048)
			(end 0.120396 0.2794)
			(stroke
				(width 0.1)
				(type default)
			)
			(layer "F.Fab")
		)
		(fp_line
			(start 0.67945 0.3048)
			(end 0.120396 0.3048)
			(stroke
				(width 0.1)
				(type default)
			)
			(layer "F.Fab")
		)
		(fp_line
			(start -0.12065 0.2794)
			(end -0.12065 0.3048)
			(stroke
				(width 0.1)
				(type default)
			)
			(layer "F.Fab")
		)
		(fp_line
			(start 0.120396 0.2794)
			(end -0.12065 0.2794)
			(stroke
				(width 0.1)
				(type default)
			)
			(layer "F.Fab")
		)
		(fp_line
			(start -0.12065 -0.2794)
			(end 0.12065 -0.2794)
			(stroke
				(width 0.1)
				(type default)
			)
			(layer "F.Fab")
		)
		(fp_line
			(start 0.12065 -0.2794)
			(end 0.12065 -0.3048)
			(stroke
				(width 0.1)
				(type default)
			)
			(layer "F.Fab")
		)
		(fp_line
			(start 0.12065 -0.3048)
			(end 0.67945 -0.3048)
			(stroke
				(width 0.1)
				(type default)
			)
			(layer "F.Fab")
		)
		(fp_line
			(start 0.67945 -0.3048)
			(end 0.67945 0.3048)
			(stroke
				(width 0.1)
				(type default)
			)
			(layer "F.Fab")
		)
		(fp_line
			(start -0.67945 -0.305054)
			(end -0.12065 -0.305054)
			(stroke
				(width 0.1)
				(type default)
			)
			(layer "F.Fab")
		)
		(fp_line
			(start -0.12065 -0.305054)
			(end -0.12065 -0.2794)
			(stroke
				(width 0.1)
				(type default)
			)
			(layer "F.Fab")
		)
		(pad "1" smd circle
			(at -0.40005 0 270)
			(size 0 0)
			(layers "F.Cu" "F.Mask" "F.Paste")
			(net "GND")
		)
		(pad "2" smd circle
			(at 0.40005 0 270)
			(size 0 0)
			(layers "F.Cu" "F.Mask" "F.Paste")
			(net "A_BMC_ADCREXT0")
		)
	)
	(footprint ""
		(layer "F.Cu")
		(at 42.672 -34.671 90)
		(property "Reference" "R56"
			(at 0 0 90)
			(layer "F.SilkS")
			(hide yes)
			(effects
				(font
					(size 1.27 1.27)
				)
			)
		)
		(property "Value" ""
			(at 0 0 90)
			(layer "F.Fab")
			(effects
				(font
					(size 1.27 1.27)
				)
			)
		)
		(duplicate_pad_numbers_are_jumpers no)
		(fp_line
			(start 0.7874 -0.4064)
			(end 0.7874 0.4064)
			(stroke
				(width 0.1524)
				(type default)
			)
			(layer "F.SilkS")
		)
		(fp_line
			(start -0.7874 -0.4064)
			(end 0.7874 -0.4064)
			(stroke
				(width 0.1524)
				(type default)
			)
			(layer "F.SilkS")
		)
		(fp_line
			(start 0.7874 0.4064)
			(end -0.7874 0.4064)
			(stroke
				(width 0.1524)
				(type default)
			)
			(layer "F.SilkS")
		)
		(fp_line
			(start -0.7874 0.4064)
			(end -0.7874 -0.4064)
			(stroke
				(width 0.1524)
				(type default)
			)
			(layer "F.SilkS")
		)
		(fp_line
			(start -0.12065 -0.305054)
			(end -0.12065 -0.2794)
			(stroke
				(width 0.1)
				(type default)
			)
			(layer "F.Fab")
		)
		(fp_line
			(start -0.67945 -0.305054)
			(end -0.12065 -0.305054)
			(stroke
				(width 0.1)
				(type default)
			)
			(layer "F.Fab")
		)
		(fp_line
			(start 0.67945 -0.3048)
			(end 0.67945 0.3048)
			(stroke
				(width 0.1)
				(type default)
			)
			(layer "F.Fab")
		)
		(fp_line
			(start 0.12065 -0.3048)
			(end 0.67945 -0.3048)
			(stroke
				(width 0.1)
				(type default)
			)
			(layer "F.Fab")
		)
		(fp_line
			(start 0.12065 -0.2794)
			(end 0.12065 -0.3048)
			(stroke
				(width 0.1)
				(type default)
			)
			(layer "F.Fab")
		)
		(fp_line
			(start -0.12065 -0.2794)
			(end 0.12065 -0.2794)
			(stroke
				(width 0.1)
				(type default)
			)
			(layer "F.Fab")
		)
		(fp_line
			(start 0.120396 0.2794)
			(end -0.12065 0.2794)
			(stroke
				(width 0.1)
				(type default)
			)
			(layer "F.Fab")
		)
		(fp_line
			(start -0.12065 0.2794)
			(end -0.12065 0.3048)
			(stroke
				(width 0.1)
				(type default)
			)
			(layer "F.Fab")
		)
		(fp_line
			(start 0.67945 0.3048)
			(end 0.120396 0.3048)
			(stroke
				(width 0.1)
				(type default)
			)
			(layer "F.Fab")
		)
		(fp_line
			(start 0.120396 0.3048)
			(end 0.120396 0.2794)
			(stroke
				(width 0.1)
				(type default)
			)
			(layer "F.Fab")
		)
		(fp_line
			(start -0.12065 0.3048)
			(end -0.67945 0.3048)
			(stroke
				(width 0.1)
				(type default)
			)
			(layer "F.Fab")
		)
		(fp_line
			(start -0.67945 0.3048)
			(end -0.67945 -0.305054)
			(stroke
				(width 0.1)
				(type default)
			)
			(layer "F.Fab")
		)
		(pad "1" smd circle
			(at -0.40005 0 90)
			(size 0 0)
			(layers "F.Cu" "F.Mask" "F.Paste")
			(net "P3V3_AUX")
		)
		(pad "2" smd circle
			(at 0.40005 0 90)
			(size 0 0)
			(layers "F.Cu" "F.Mask" "F.Paste")
			(net "FM_BIOS_DEBUG_EN_R_N")
		)
	)
	(footprint ""
		(layer "F.Cu")
		(at 5.01015 -65.983358)
		(property "Reference" "PR532"
			(at 0 0 0)
			(layer "F.SilkS")
			(hide yes)
			(effects
				(font
					(size 1.27 1.27)
				)
			)
		)
		(property "Value" ""
			(at 0 0 0)
			(layer "F.Fab")
			(effects
				(font
					(size 1.27 1.27)
				)
			)
		)
		(duplicate_pad_numbers_are_jumpers no)
		(fp_line
			(start -0.7874 -0.4064)
			(end 0.7874 -0.4064)
			(stroke
				(width 0.1524)
				(type default)
			)
			(layer "F.SilkS")
		)
		(fp_line
			(start -0.7874 0.4064)
			(end -0.7874 -0.4064)
			(stroke
				(width 0.1524)
				(type default)
			)
			(layer "F.SilkS")
		)
		(fp_line
			(start 0.7874 -0.4064)
			(end 0.7874 0.4064)
			(stroke
				(width 0.1524)
				(type default)
			)
			(layer "F.SilkS")
		)
		(fp_line
			(start 0.7874 0.4064)
			(end -0.7874 0.4064)
			(stroke
				(width 0.1524)
				(type default)
			)
			(layer "F.SilkS")
		)
		(fp_line
			(start -0.67945 -0.305054)
			(end -0.12065 -0.305054)
			(stroke
				(width 0.1)
				(type default)
			)
			(layer "F.Fab")
		)
		(fp_line
			(start -0.67945 0.3048)
			(end -0.67945 -0.305054)
			(stroke
				(width 0.1)
				(type default)
			)
			(layer "F.Fab")
		)
		(fp_line
			(start -0.12065 -0.305054)
			(end -0.12065 -0.2794)
			(stroke
				(width 0.1)
				(type default)
			)
			(layer "F.Fab")
		)
		(fp_line
			(start -0.12065 -0.2794)
			(end 0.12065 -0.2794)
			(stroke
				(width 0.1)
				(type default)
			)
			(layer "F.Fab")
		)
		(fp_line
			(start -0.12065 0.2794)
			(end -0.12065 0.3048)
			(stroke
				(width 0.1)
				(type default)
			)
			(layer "F.Fab")
		)
		(fp_line
			(start -0.12065 0.3048)
			(end -0.67945 0.3048)
			(stroke
				(width 0.1)
				(type default)
			)
			(layer "F.Fab")
		)
		(fp_line
			(start 0.120396 0.2794)
			(end -0.12065 0.2794)
			(stroke
				(width 0.1)
				(type default)
			)
			(layer "F.Fab")
		)
		(fp_line
			(start 0.120396 0.3048)
			(end 0.120396 0.2794)
			(stroke
				(width 0.1)
				(type default)
			)
			(layer "F.Fab")
		)
		(fp_line
			(start 0.12065 -0.3048)
			(end 0.67945 -0.3048)
			(stroke
				(width 0.1)
				(type default)
			)
			(layer "F.Fab")
		)
		(fp_line
			(start 0.12065 -0.2794)
			(end 0.12065 -0.3048)
			(stroke
				(width 0.1)
				(type default)
			)
			(layer "F.Fab")
		)
		(fp_line
			(start 0.67945 -0.3048)
			(end 0.67945 0.3048)
			(stroke
				(width 0.1)
				(type default)
			)
			(layer "F.Fab")
		)
		(fp_line
			(start 0.67945 0.3048)
			(end 0.120396 0.3048)
			(stroke
				(width 0.1)
				(type default)
			)
			(layer "F.Fab")
		)
		(pad "1" smd circle
			(at -0.40005 0)
			(size 0 0)
			(layers "F.Cu" "F.Mask" "F.Paste")
			(net "GND")
		)
		(pad "2" smd circle
			(at 0.40005 0)
			(size 0 0)
			(layers "F.Cu" "F.Mask" "F.Paste")
			(net "P3V3_AUX_MODE")
		)
	)
	(footprint ""
		(layer "F.Cu")
		(at 74.09815 -93.347032)
		(property "Reference" "R50"
			(at 0 0 0)
			(layer "F.SilkS")
			(hide yes)
			(effects
				(font
					(size 1.27 1.27)
				)
			)
		)
		(property "Value" ""
			(at 0 0 0)
			(layer "F.Fab")
			(effects
				(font
					(size 1.27 1.27)
				)
			)
		)
		(duplicate_pad_numbers_are_jumpers no)
		(fp_line
			(start -0.7874 -0.4064)
			(end 0.7874 -0.4064)
			(stroke
				(width 0.1524)
				(type default)
			)
			(layer "F.SilkS")
		)
		(fp_line
			(start -0.7874 0.4064)
			(end -0.7874 -0.4064)
			(stroke
				(width 0.1524)
				(type default)
			)
			(layer "F.SilkS")
		)
		(fp_line
			(start 0.7874 -0.4064)
			(end 0.7874 0.4064)
			(stroke
				(width 0.1524)
				(type default)
			)
			(layer "F.SilkS")
		)
		(fp_line
			(start 0.7874 0.4064)
			(end -0.7874 0.4064)
			(stroke
				(width 0.1524)
				(type default)
			)
			(layer "F.SilkS")
		)
		(fp_line
			(start -0.67945 -0.305054)
			(end -0.12065 -0.305054)
			(stroke
				(width 0.1)
				(type default)
			)
			(layer "F.Fab")
		)
		(fp_line
			(start -0.67945 0.3048)
			(end -0.67945 -0.305054)
			(stroke
				(width 0.1)
				(type default)
			)
			(layer "F.Fab")
		)
		(fp_line
			(start -0.12065 -0.305054)
			(end -0.12065 -0.2794)
			(stroke
				(width 0.1)
				(type default)
			)
			(layer "F.Fab")
		)
		(fp_line
			(start -0.12065 -0.2794)
			(end 0.12065 -0.2794)
			(stroke
				(width 0.1)
				(type default)
			)
			(layer "F.Fab")
		)
		(fp_line
			(start -0.12065 0.2794)
			(end -0.12065 0.3048)
			(stroke
				(width 0.1)
				(type default)
			)
			(layer "F.Fab")
		)
		(fp_line
			(start -0.12065 0.3048)
			(end -0.67945 0.3048)
			(stroke
				(width 0.1)
				(type default)
			)
			(layer "F.Fab")
		)
		(fp_line
			(start 0.120396 0.2794)
			(end -0.12065 0.2794)
			(stroke
				(width 0.1)
				(type default)
			)
			(layer "F.Fab")
		)
		(fp_line
			(start 0.120396 0.3048)
			(end 0.120396 0.2794)
			(stroke
				(width 0.1)
				(type default)
			)
			(layer "F.Fab")
		)
		(fp_line
			(start 0.12065 -0.3048)
			(end 0.67945 -0.3048)
			(stroke
				(width 0.1)
				(type default)
			)
			(layer "F.Fab")
		)
		(fp_line
			(start 0.12065 -0.2794)
			(end 0.12065 -0.3048)
			(stroke
				(width 0.1)
				(type default)
			)
			(layer "F.Fab")
		)
		(fp_line
			(start 0.67945 -0.3048)
			(end 0.67945 0.3048)
			(stroke
				(width 0.1)
				(type default)
			)
			(layer "F.Fab")
		)
		(fp_line
			(start 0.67945 0.3048)
			(end 0.120396 0.3048)
			(stroke
				(width 0.1)
				(type default)
			)
			(layer "F.Fab")
		)
		(pad "1" smd circle
			(at -0.40005 0)
			(size 0 0)
			(layers "F.Cu" "F.Mask" "F.Paste")
			(net "P3V3_AUX")
		)
		(pad "2" smd circle
			(at 0.40005 0)
			(size 0 0)
			(layers "F.Cu" "F.Mask" "F.Paste")
			(net "FM_TPM_PRSNT_1_N")
		)
	)
	(footprint ""
		(layer "F.Cu")
		(at 68.4784 -85.7758)
		(property "Reference" ""
			(at 0 0 0)
			(layer "F.SilkS")
			(hide yes)
			(effects
				(font
					(size 1.27 1.27)
				)
			)
		)
		(property "Value" ""
			(at 0 0 0)
			(layer "F.Fab")
			(effects
				(font
					(size 1.27 1.27)
				)
			)
		)
		(duplicate_pad_numbers_are_jumpers no)
		(pad "1" smd circle
			(at 0 0)
			(size 0.9906 0.9906)
			(layers "F.Cu" "F.Mask" "F.Paste")
			(net "Net_327")
		)
		(zone
			(layer "F.Cu")
			(hatch none 0.5)
			(connect_pads
				(clearance 0)
			)
			(min_thickness 0.25)
			(keepout
				(tracks not_allowed)
				(vias allowed)
				(pads allowed)
				(copperpour not_allowed)
				(footprints allowed)
			)
			(placement
				(enabled no)
				(sheetname "")
			)
			(fill
				(thermal_gap 0.5)
				(thermal_bridge_width 0.5)
				(island_removal_mode 0)
			)
			(polygon
				(pts
					(arc
						(start 70.104 -85.7758)
						(mid 66.8528 -85.7758)
						(end 70.104 -85.7758)
					)
				)
			)
		)
	)
	(footprint ""
		(layer "F.Cu")
		(at 54.229 -98.425 -90)
		(property "Reference" "R636"
			(at 0 0 270)
			(layer "F.SilkS")
			(hide yes)
			(effects
				(font
					(size 1.27 1.27)
				)
			)
		)
		(property "Value" ""
			(at 0 0 270)
			(layer "F.Fab")
			(effects
				(font
					(size 1.27 1.27)
				)
			)
		)
		(duplicate_pad_numbers_are_jumpers no)
		(fp_line
			(start -0.7874 0.4064)
			(end -0.7874 -0.4064)
			(stroke
				(width 0.1524)
				(type default)
			)
			(layer "F.SilkS")
		)
		(fp_line
			(start 0.7874 0.4064)
			(end -0.7874 0.4064)
			(stroke
				(width 0.1524)
				(type default)
			)
			(layer "F.SilkS")
		)
		(fp_line
			(start -0.7874 -0.4064)
			(end 0.7874 -0.4064)
			(stroke
				(width 0.1524)
				(type default)
			)
			(layer "F.SilkS")
		)
		(fp_line
			(start 0.7874 -0.4064)
			(end 0.7874 0.4064)
			(stroke
				(width 0.1524)
				(type default)
			)
			(layer "F.SilkS")
		)
		(fp_line
			(start -0.67945 0.3048)
			(end -0.67945 -0.305054)
			(stroke
				(width 0.1)
				(type default)
			)
			(layer "F.Fab")
		)
		(fp_line
			(start -0.12065 0.3048)
			(end -0.67945 0.3048)
			(stroke
				(width 0.1)
				(type default)
			)
			(layer "F.Fab")
		)
		(fp_line
			(start 0.120396 0.3048)
			(end 0.120396 0.2794)
			(stroke
				(width 0.1)
				(type default)
			)
			(layer "F.Fab")
		)
		(fp_line
			(start 0.67945 0.3048)
			(end 0.120396 0.3048)
			(stroke
				(width 0.1)
				(type default)
			)
			(layer "F.Fab")
		)
		(fp_line
			(start -0.12065 0.2794)
			(end -0.12065 0.3048)
			(stroke
				(width 0.1)
				(type default)
			)
			(layer "F.Fab")
		)
		(fp_line
			(start 0.120396 0.2794)
			(end -0.12065 0.2794)
			(stroke
				(width 0.1)
				(type default)
			)
			(layer "F.Fab")
		)
		(fp_line
			(start -0.12065 -0.2794)
			(end 0.12065 -0.2794)
			(stroke
				(width 0.1)
				(type default)
			)
			(layer "F.Fab")
		)
		(fp_line
			(start 0.12065 -0.2794)
			(end 0.12065 -0.3048)
			(stroke
				(width 0.1)
				(type default)
			)
			(layer "F.Fab")
		)
		(fp_line
			(start 0.12065 -0.3048)
			(end 0.67945 -0.3048)
			(stroke
				(width 0.1)
				(type default)
			)
			(layer "F.Fab")
		)
		(fp_line
			(start 0.67945 -0.3048)
			(end 0.67945 0.3048)
			(stroke
				(width 0.1)
				(type default)
			)
			(layer "F.Fab")
		)
		(fp_line
			(start -0.67945 -0.305054)
			(end -0.12065 -0.305054)
			(stroke
				(width 0.1)
				(type default)
			)
			(layer "F.Fab")
		)
		(fp_line
			(start -0.12065 -0.305054)
			(end -0.12065 -0.2794)
			(stroke
				(width 0.1)
				(type default)
			)
			(layer "F.Fab")
		)
		(pad "1" smd circle
			(at -0.40005 0 270)
			(size 0 0)
			(layers "F.Cu" "F.Mask" "F.Paste")
			(net "RST_EXTRST_N")
		)
		(pad "2" smd circle
			(at 0.40005 0 270)
			(size 0 0)
			(layers "F.Cu" "F.Mask" "F.Paste")
			(net "RST_BMC_EXTRST_R2_N")
		)
	)
	(footprint ""
		(layer "F.Cu")
		(at 29.6164 -25.908 180)
		(property "Reference" "R16"
			(at 0 0 180)
			(layer "F.SilkS")
			(hide yes)
			(effects
				(font
					(size 1.27 1.27)
				)
			)
		)
		(property "Value" ""
			(at 0 0 180)
			(layer "F.Fab")
			(effects
				(font
					(size 1.27 1.27)
				)
			)
		)
		(duplicate_pad_numbers_are_jumpers no)
		(fp_line
			(start 0.7874 0.4064)
			(end -0.7874 0.4064)
			(stroke
				(width 0.1524)
				(type default)
			)
			(layer "F.SilkS")
		)
		(fp_line
			(start 0.7874 -0.4064)
			(end 0.7874 0.4064)
			(stroke
				(width 0.1524)
				(type default)
			)
			(layer "F.SilkS")
		)
		(fp_line
			(start -0.7874 0.4064)
			(end -0.7874 -0.4064)
			(stroke
				(width 0.1524)
				(type default)
			)
			(layer "F.SilkS")
		)
		(fp_line
			(start -0.7874 -0.4064)
			(end 0.7874 -0.4064)
			(stroke
				(width 0.1524)
				(type default)
			)
			(layer "F.SilkS")
		)
		(fp_line
			(start 0.67945 0.3048)
			(end 0.120396 0.3048)
			(stroke
				(width 0.1)
				(type default)
			)
			(layer "F.Fab")
		)
		(fp_line
			(start 0.67945 -0.3048)
			(end 0.67945 0.3048)
			(stroke
				(width 0.1)
				(type default)
			)
			(layer "F.Fab")
		)
		(fp_line
			(start 0.12065 -0.2794)
			(end 0.12065 -0.3048)
			(stroke
				(width 0.1)
				(type default)
			)
			(layer "F.Fab")
		)
		(fp_line
			(start 0.12065 -0.3048)
			(end 0.67945 -0.3048)
			(stroke
				(width 0.1)
				(type default)
			)
			(layer "F.Fab")
		)
		(fp_line
			(start 0.120396 0.3048)
			(end 0.120396 0.2794)
			(stroke
				(width 0.1)
				(type default)
			)
			(layer "F.Fab")
		)
		(fp_line
			(start 0.120396 0.2794)
			(end -0.12065 0.2794)
			(stroke
				(width 0.1)
				(type default)
			)
			(layer "F.Fab")
		)
		(fp_line
			(start -0.12065 0.3048)
			(end -0.67945 0.3048)
			(stroke
				(width 0.1)
				(type default)
			)
			(layer "F.Fab")
		)
		(fp_line
			(start -0.12065 0.2794)
			(end -0.12065 0.3048)
			(stroke
				(width 0.1)
				(type default)
			)
			(layer "F.Fab")
		)
		(fp_line
			(start -0.12065 -0.2794)
			(end 0.12065 -0.2794)
			(stroke
				(width 0.1)
				(type default)
			)
			(layer "F.Fab")
		)
		(fp_line
			(start -0.12065 -0.305054)
			(end -0.12065 -0.2794)
			(stroke
				(width 0.1)
				(type default)
			)
			(layer "F.Fab")
		)
		(fp_line
			(start -0.67945 0.3048)
			(end -0.67945 -0.305054)
			(stroke
				(width 0.1)
				(type default)
			)
			(layer "F.Fab")
		)
		(fp_line
			(start -0.67945 -0.305054)
			(end -0.12065 -0.305054)
			(stroke
				(width 0.1)
				(type default)
			)
			(layer "F.Fab")
		)
		(pad "1" smd circle
			(at -0.40005 0 180)
			(size 0 0)
			(layers "F.Cu" "F.Mask" "F.Paste")
			(net "V_BMC_LS_DDC_SCL_R")
		)
		(pad "2" smd circle
			(at 0.40005 0 180)
			(size 0 0)
			(layers "F.Cu" "F.Mask" "F.Paste")
			(net "CRT_VCC5")
		)
	)
)
